(kicad_pcb
	(version 20260206)
	(generator "pcbnew")
	(generator_version "10.0")
	(general
		(thickness 1.6)
		(legacy_teardrops no)
	)
	(paper "A4")
	(title_block
		(title "pdpb — Lightning_PDPB_BRD.brd")
		(comment 1 "Lightning (Wiwynn / Facebook NVMe JBOF) / footprints 276-283 of 1140")
	)
	(layers
		(0 "F.Cu" signal "TOP")
		(4 "In1.Cu" signal "L2GND")
		(6 "In2.Cu" signal "L3")
		(8 "In3.Cu" signal "L4VCC")
		(10 "In4.Cu" signal "L5VCC")
		(12 "In5.Cu" signal "L6")
		(14 "In6.Cu" signal "L7GND")
		(2 "B.Cu" signal "BOTTOM")
		(9 "F.Adhes" user "F.Adhesive")
		(11 "B.Adhes" user "B.Adhesive")
		(13 "F.Paste" user "Package Geometry/Pastemask Top")
		(15 "B.Paste" user "Package Geometry/Pastemask Bottom")
		(5 "F.SilkS" user "Ref Des/Silkscreen Top")
		(7 "B.SilkS" user "Ref Des/Silkscreen Bottom")
		(1 "F.Mask" user "Board Geometry/Soldermask Top")
		(3 "B.Mask" user "Board Geometry/Soldermask Bottom")
		(17 "Dwgs.User" user "User.Drawings")
		(19 "Cmts.User" user "User.Comments")
		(21 "Eco1.User" user "User.Eco1")
		(23 "Eco2.User" user "User.Eco2")
		(25 "Edge.Cuts" user "Board Geometry/Outline")
		(27 "Margin" user)
		(31 "F.CrtYd" user "Package Geometry/Place Bound Top")
		(29 "B.CrtYd" user "Package Geometry/Place Bound Bottom")
		(35 "F.Fab" user "Ref Des/Assembly Top")
		(33 "B.Fab" user "Ref Des/Assembly Bottom")
	)
	(footprint ""
		(layer "F.Cu")
		(at 221.361 -474.218 180)
		(property "Reference" "PC1189"
			(at 0 0 180)
			(layer "F.SilkS")
			(hide yes)
			(effects
				(font
					(size 1.27 1.27)
				)
			)
		)
		(property "Value" "SCD1U25V3KX-GP"
			(at 0 -2.8194 180)
			(unlocked yes)
			(layer "F.Fab")
			(hide yes)
			(effects
				(font
					(size 1.016 1.016)
					(thickness 0.1524)
				)
			)
		)
		(property "Device Type" "C603H36"
			(at 0 -4.3434 180)
			(unlocked yes)
			(layer "F.Fab")
			(hide yes)
			(effects
				(font
					(size 1.016 1.016)
					(thickness 0.1524)
				)
			)
		)
		(duplicate_pad_numbers_are_jumpers no)
		(fp_line
			(start 0.508 0)
			(end -0.508 0)
			(stroke
				(width 0.2032)
				(type default)
			)
			(layer "F.SilkS")
		)
		(fp_rect
			(start -0.5842 1.3335)
			(end 0.5842 -1.3335)
			(stroke
				(width 0)
				(type default)
			)
			(fill no)
			(layer "F.CrtYd")
		)
		(fp_rect
			(start -0.5842 1.3335)
			(end 0.5842 -1.3335)
			(stroke
				(width 0)
				(type default)
			)
			(fill no)
			(layer "F.Fab")
		)
		(pad "1" smd custom
			(at 0 -0.762 180)
			(size 0.2159 0.2159)
			(layers "F.Cu" "F.Mask" "F.Paste")
			(net "P3V3")
			(options
				(clearance outline)
				(anchor circle)
			)
			(primitives
				(gr_poly
					(pts
						(arc
							(start -0.3302 -0.4318)
							(mid -0.402042 -0.402042)
							(end -0.4318 -0.3302)
						)
						(arc
							(start -0.4318 0.3302)
							(mid -0.402042 0.402042)
							(end -0.3302 0.4318)
						)
						(arc
							(start 0.3302 0.4318)
							(mid 0.402042 0.402042)
							(end 0.4318 0.3302)
						)
						(arc
							(start 0.4318 -0.3302)
							(mid 0.402042 -0.402042)
							(end 0.3302 -0.4318)
						)
					)
					(width 0)
					(fill yes)
				)
			)
		)
		(pad "2" smd custom
			(at 0 0.762 180)
			(size 0.2159 0.2159)
			(layers "F.Cu" "F.Mask" "F.Paste")
			(net "GND")
			(options
				(clearance outline)
				(anchor circle)
			)
			(primitives
				(gr_poly
					(pts
						(arc
							(start -0.3302 -0.4318)
							(mid -0.402042 -0.402042)
							(end -0.4318 -0.3302)
						)
						(arc
							(start -0.4318 0.3302)
							(mid -0.402042 0.402042)
							(end -0.3302 0.4318)
						)
						(arc
							(start 0.3302 0.4318)
							(mid 0.402042 0.402042)
							(end 0.4318 0.3302)
						)
						(arc
							(start 0.4318 -0.3302)
							(mid 0.402042 -0.402042)
							(end 0.3302 -0.4318)
						)
					)
					(width 0)
					(fill yes)
				)
			)
		)
	)
	(footprint ""
		(layer "F.Cu")
		(at 85.5472 -210.3247 180)
		(property "Reference" "R9969"
			(at 0 0 180)
			(layer "F.SilkS")
			(hide yes)
			(effects
				(font
					(size 1.27 1.27)
				)
			)
		)
		(property "Value" "100R1F-GP"
			(at -3.3274 -1.3335 180)
			(unlocked yes)
			(layer "F.Fab")
			(hide yes)
			(effects
				(font
					(size 1.016 1.016)
					(thickness 0.1524)
				)
			)
		)
		(property "Device Type" "R0201H12"
			(at -3.3274 -2.8575 180)
			(unlocked yes)
			(layer "F.Fab")
			(hide yes)
			(effects
				(font
					(size 1.016 1.016)
					(thickness 0.1524)
				)
			)
		)
		(duplicate_pad_numbers_are_jumpers no)
		(fp_rect
			(start -0.2794 0.6477)
			(end 0.2794 -0.6477)
			(stroke
				(width 0)
				(type default)
			)
			(fill no)
			(layer "F.CrtYd")
		)
		(fp_rect
			(start -0.2794 0.6477)
			(end 0.2794 -0.6477)
			(stroke
				(width 0)
				(type default)
			)
			(fill no)
			(layer "F.Fab")
		)
		(pad "1" smd custom
			(at 0 -0.2794 180)
			(size 0.0762 0.0762)
			(layers "F.Cu" "F.Mask" "F.Paste")
			(net "PE_100M_CLK2_N")
			(options
				(clearance outline)
				(anchor circle)
			)
			(primitives
				(gr_poly
					(pts
						(arc
							(start 0.1524 -0.127)
							(mid 0.137521 -0.162921)
							(end 0.1016 -0.1778)
						)
						(arc
							(start -0.1016 -0.1778)
							(mid -0.137521 -0.162921)
							(end -0.1524 -0.127)
						)
						(arc
							(start -0.1524 0.127)
							(mid -0.137521 0.162921)
							(end -0.1016 0.1778)
						)
						(arc
							(start 0.1016 0.1778)
							(mid 0.137521 0.162921)
							(end 0.1524 0.127)
						)
					)
					(width 0)
					(fill yes)
				)
			)
		)
		(pad "2" smd custom
			(at 0 0.2794 180)
			(size 0.0762 0.0762)
			(layers "F.Cu" "F.Mask" "F.Paste")
			(net "PE_100M_CLK2_P")
			(options
				(clearance outline)
				(anchor circle)
			)
			(primitives
				(gr_poly
					(pts
						(arc
							(start 0.1524 -0.127)
							(mid 0.137521 -0.162921)
							(end 0.1016 -0.1778)
						)
						(arc
							(start -0.1016 -0.1778)
							(mid -0.137521 -0.162921)
							(end -0.1524 -0.127)
						)
						(arc
							(start -0.1524 0.127)
							(mid -0.137521 0.162921)
							(end -0.1016 0.1778)
						)
						(arc
							(start 0.1016 0.1778)
							(mid 0.137521 0.162921)
							(end 0.1524 0.127)
						)
					)
					(width 0)
					(fill yes)
				)
			)
		)
	)
	(footprint ""
		(layer "F.Cu")
		(at 21.5138 -192.532)
		(property "Reference" "D26"
			(at 0 0 0)
			(layer "F.SilkS")
			(hide yes)
			(effects
				(font
					(size 1.27 1.27)
				)
			)
		)
		(property "Value" "RB551V30-1-GP"
			(at 0 -6.7818 0)
			(unlocked yes)
			(layer "F.Fab")
			(hide yes)
			(effects
				(font
					(size 1.016 1.016)
					(thickness 0.1524)
				)
			)
		)
		(property "Device Type" "SOD323AKH44"
			(at 0 -8.6868 0)
			(unlocked yes)
			(layer "F.Fab")
			(hide yes)
			(effects
				(font
					(size 1.016 1.016)
					(thickness 0.1524)
				)
			)
		)
		(duplicate_pad_numbers_are_jumpers no)
		(fp_line
			(start -0.889 -1.9304)
			(end 0.889 -1.9304)
			(stroke
				(width 0.1524)
				(type default)
			)
			(layer "F.SilkS")
		)
		(fp_line
			(start -0.889 2.159)
			(end -0.889 -1.9304)
			(stroke
				(width 0.1524)
				(type default)
			)
			(layer "F.SilkS")
		)
		(fp_line
			(start 0.762 2.0574)
			(end -0.762 2.0574)
			(stroke
				(width 0.508)
				(type default)
			)
			(layer "F.SilkS")
		)
		(fp_line
			(start 0.889 -1.9304)
			(end 0.889 2.159)
			(stroke
				(width 0.1524)
				(type default)
			)
			(layer "F.SilkS")
		)
		(fp_line
			(start 0.889 2.159)
			(end -0.889 2.159)
			(stroke
				(width 0.1524)
				(type default)
			)
			(layer "F.SilkS")
		)
		(fp_rect
			(start -1.016 2.3114)
			(end 1.016 -2.0066)
			(stroke
				(width 0)
				(type default)
			)
			(fill no)
			(layer "F.CrtYd")
		)
		(fp_poly
			(pts
				(xy -1.016 -2.0066) (xy 1.016 -2.0066) (xy 1.016 2.3114) (xy -1.016 2.3114)
			)
			(stroke
				(width 0)
				(type default)
			)
			(fill no)
			(layer "F.Fab")
		)
		(pad "A" smd rect
			(at 0 -1.143)
			(size 0.5588 1.016)
			(layers "F.Cu" "F.Mask" "F.Paste")
			(net "SW_SSD8_R")
		)
		(pad "K" smd rect
			(at 0 1.143)
			(size 0.5588 1.016)
			(layers "F.Cu" "F.Mask" "F.Paste")
			(net "SW_SSD8_N")
		)
	)
	(footprint ""
		(layer "F.Cu")
		(at 85.471 -98.806 90)
		(property "Reference" "R9121"
			(at 0 0 90)
			(layer "F.SilkS")
			(hide yes)
			(effects
				(font
					(size 1.27 1.27)
				)
			)
		)
		(property "Value" "4K7R2F-GP"
			(at 0.064008 -3.993896 90)
			(unlocked yes)
			(layer "F.Fab")
			(hide yes)
			(effects
				(font
					(size 1.016 1.016)
					(thickness 0.1524)
				)
			)
		)
		(property "Device Type" "R402H16"
			(at 0.064008 -5.517896 90)
			(unlocked yes)
			(layer "F.Fab")
			(hide yes)
			(effects
				(font
					(size 1.016 1.016)
					(thickness 0.1524)
				)
			)
		)
		(duplicate_pad_numbers_are_jumpers no)
		(fp_line
			(start 0.508 -0.9398)
			(end -0.508 -0.9398)
			(stroke
				(width 0.1524)
				(type default)
			)
			(layer "F.SilkS")
		)
		(fp_line
			(start -0.508 -0.9398)
			(end -0.508 0.9398)
			(stroke
				(width 0.1524)
				(type default)
			)
			(layer "F.SilkS")
		)
		(fp_rect
			(start -0.508 0.9398)
			(end 0.508 -0.9398)
			(stroke
				(width 0)
				(type default)
			)
			(fill no)
			(layer "F.CrtYd")
		)
		(fp_rect
			(start -0.508 0.9398)
			(end 0.508 -0.9398)
			(stroke
				(width 0)
				(type default)
			)
			(fill no)
			(layer "F.Fab")
		)
		(pad "1" smd custom
			(at 0 -0.4445 90)
			(size 0.1397 0.1397)
			(layers "F.Cu" "F.Mask" "F.Paste")
			(net "VDD_DIFF_4")
			(options
				(clearance outline)
				(anchor circle)
			)
			(primitives
				(gr_poly
					(pts
						(arc
							(start -0.1778 -0.2794)
							(mid -0.249642 -0.249642)
							(end -0.2794 -0.1778)
						)
						(arc
							(start -0.2794 0.1778)
							(mid -0.249642 0.249642)
							(end -0.1778 0.2794)
						)
						(arc
							(start 0.1778 0.2794)
							(mid 0.249642 0.249642)
							(end 0.2794 0.1778)
						)
						(arc
							(start 0.2794 -0.1778)
							(mid 0.249642 -0.249642)
							(end 0.1778 -0.2794)
						)
					)
					(width 0)
					(fill yes)
				)
			)
		)
		(pad "2" smd custom
			(at 0 0.4445 90)
			(size 0.1397 0.1397)
			(layers "F.Cu" "F.Mask" "F.Paste")
			(net "CLK_BUF_EU4_SMB_A0_TRI")
			(options
				(clearance outline)
				(anchor circle)
			)
			(primitives
				(gr_poly
					(pts
						(arc
							(start -0.1778 -0.2794)
							(mid -0.249642 -0.249642)
							(end -0.2794 -0.1778)
						)
						(arc
							(start -0.2794 0.1778)
							(mid -0.249642 0.249642)
							(end -0.1778 0.2794)
						)
						(arc
							(start 0.1778 0.2794)
							(mid 0.249642 0.249642)
							(end 0.2794 0.1778)
						)
						(arc
							(start 0.2794 -0.1778)
							(mid 0.249642 -0.249642)
							(end 0.1778 -0.2794)
						)
					)
					(width 0)
					(fill yes)
				)
			)
		)
	)
	(footprint ""
		(layer "F.Cu")
		(at 209.296 -190.119 180)
		(property "Reference" "R569"
			(at 0 0 180)
			(layer "F.SilkS")
			(hide yes)
			(effects
				(font
					(size 1.27 1.27)
				)
			)
		)
		(property "Value" "300KR2F-GP"
			(at 0.064008 -3.993896 180)
			(unlocked yes)
			(layer "F.Fab")
			(hide yes)
			(effects
				(font
					(size 1.016 1.016)
					(thickness 0.1524)
				)
			)
		)
		(property "Device Type" "R402H16"
			(at 0.064008 -5.517896 180)
			(unlocked yes)
			(layer "F.Fab")
			(hide yes)
			(effects
				(font
					(size 1.016 1.016)
					(thickness 0.1524)
				)
			)
		)
		(duplicate_pad_numbers_are_jumpers no)
		(fp_line
			(start 0.508 -0.9398)
			(end -0.508 -0.9398)
			(stroke
				(width 0.1524)
				(type default)
			)
			(layer "F.SilkS")
		)
		(fp_line
			(start -0.508 -0.9398)
			(end -0.508 0.9398)
			(stroke
				(width 0.1524)
				(type default)
			)
			(layer "F.SilkS")
		)
		(fp_rect
			(start -0.508 0.9398)
			(end 0.508 -0.9398)
			(stroke
				(width 0)
				(type default)
			)
			(fill no)
			(layer "F.CrtYd")
		)
		(fp_rect
			(start -0.508 0.9398)
			(end 0.508 -0.9398)
			(stroke
				(width 0)
				(type default)
			)
			(fill no)
			(layer "F.Fab")
		)
		(pad "1" smd custom
			(at 0 -0.4445 180)
			(size 0.1397 0.1397)
			(layers "F.Cu" "F.Mask" "F.Paste")
			(net "SW_SSD3_N")
			(options
				(clearance outline)
				(anchor circle)
			)
			(primitives
				(gr_poly
					(pts
						(arc
							(start -0.1778 -0.2794)
							(mid -0.249642 -0.249642)
							(end -0.2794 -0.1778)
						)
						(arc
							(start -0.2794 0.1778)
							(mid -0.249642 0.249642)
							(end -0.1778 0.2794)
						)
						(arc
							(start 0.1778 0.2794)
							(mid 0.249642 0.249642)
							(end 0.2794 0.1778)
						)
						(arc
							(start 0.2794 -0.1778)
							(mid 0.249642 -0.249642)
							(end 0.1778 -0.2794)
						)
					)
					(width 0)
					(fill yes)
				)
			)
		)
		(pad "2" smd custom
			(at 0 0.4445 180)
			(size 0.1397 0.1397)
			(layers "F.Cu" "F.Mask" "F.Paste")
			(net "P12V")
			(options
				(clearance outline)
				(anchor circle)
			)
			(primitives
				(gr_poly
					(pts
						(arc
							(start -0.1778 -0.2794)
							(mid -0.249642 -0.249642)
							(end -0.2794 -0.1778)
						)
						(arc
							(start -0.2794 0.1778)
							(mid -0.249642 0.249642)
							(end -0.1778 0.2794)
						)
						(arc
							(start 0.1778 0.2794)
							(mid 0.249642 0.249642)
							(end 0.2794 0.1778)
						)
						(arc
							(start 0.2794 -0.1778)
							(mid 0.249642 -0.249642)
							(end 0.1778 -0.2794)
						)
					)
					(width 0)
					(fill yes)
				)
			)
		)
	)
	(footprint ""
		(layer "F.Cu")
		(at 49.276 -246.253 -90)
		(property "Reference" "R9899"
			(at 0 0 270)
			(layer "F.SilkS")
			(hide yes)
			(effects
				(font
					(size 1.27 1.27)
				)
			)
		)
		(property "Value" "1K82R2F-1-GP"
			(at 0.064008 -3.993896 270)
			(unlocked yes)
			(layer "F.Fab")
			(hide yes)
			(effects
				(font
					(size 1.016 1.016)
					(thickness 0.1524)
				)
			)
		)
		(property "Device Type" "R402H16"
			(at 0.064008 -5.517896 270)
			(unlocked yes)
			(layer "F.Fab")
			(hide yes)
			(effects
				(font
					(size 1.016 1.016)
					(thickness 0.1524)
				)
			)
		)
		(duplicate_pad_numbers_are_jumpers no)
		(fp_line
			(start -0.508 -0.9398)
			(end -0.508 0.9398)
			(stroke
				(width 0.1524)
				(type default)
			)
			(layer "F.SilkS")
		)
		(fp_line
			(start 0.508 -0.9398)
			(end -0.508 -0.9398)
			(stroke
				(width 0.1524)
				(type default)
			)
			(layer "F.SilkS")
		)
		(fp_rect
			(start -0.508 0.9398)
			(end 0.508 -0.9398)
			(stroke
				(width 0)
				(type default)
			)
			(fill no)
			(layer "F.CrtYd")
		)
		(fp_rect
			(start -0.508 0.9398)
			(end 0.508 -0.9398)
			(stroke
				(width 0)
				(type default)
			)
			(fill no)
			(layer "F.Fab")
		)
		(pad "1" smd custom
			(at 0 -0.4445 270)
			(size 0.1397 0.1397)
			(layers "F.Cu" "F.Mask" "F.Paste")
			(net "P12V")
			(options
				(clearance outline)
				(anchor circle)
			)
			(primitives
				(gr_poly
					(pts
						(arc
							(start -0.1778 -0.2794)
							(mid -0.249642 -0.249642)
							(end -0.2794 -0.1778)
						)
						(arc
							(start -0.2794 0.1778)
							(mid -0.249642 0.249642)
							(end -0.1778 0.2794)
						)
						(arc
							(start 0.1778 0.2794)
							(mid 0.249642 0.249642)
							(end 0.2794 0.1778)
						)
						(arc
							(start 0.2794 -0.1778)
							(mid 0.249642 -0.249642)
							(end 0.1778 -0.2794)
						)
					)
					(width 0)
					(fill yes)
				)
			)
		)
		(pad "2" smd custom
			(at 0 0.4445 270)
			(size 0.1397 0.1397)
			(layers "F.Cu" "F.Mask" "F.Paste")
			(net "DRV_ACT_7")
			(options
				(clearance outline)
				(anchor circle)
			)
			(primitives
				(gr_poly
					(pts
						(arc
							(start -0.1778 -0.2794)
							(mid -0.249642 -0.249642)
							(end -0.2794 -0.1778)
						)
						(arc
							(start -0.2794 0.1778)
							(mid -0.249642 0.249642)
							(end -0.1778 0.2794)
						)
						(arc
							(start 0.1778 0.2794)
							(mid 0.249642 0.249642)
							(end 0.2794 0.1778)
						)
						(arc
							(start 0.2794 -0.1778)
							(mid 0.249642 -0.249642)
							(end 0.1778 -0.2794)
						)
					)
					(width 0)
					(fill yes)
				)
			)
		)
	)
	(footprint ""
		(layer "F.Cu")
		(at 21.336 -396.24)
		(property "Reference" "D24"
			(at 0 0 0)
			(layer "F.SilkS")
			(hide yes)
			(effects
				(font
					(size 1.27 1.27)
				)
			)
		)
		(property "Value" "RB551V30-1-GP"
			(at 0 -6.7818 0)
			(unlocked yes)
			(layer "F.Fab")
			(hide yes)
			(effects
				(font
					(size 1.016 1.016)
					(thickness 0.1524)
				)
			)
		)
		(property "Device Type" "SOD323AKH44"
			(at 0 -8.6868 0)
			(unlocked yes)
			(layer "F.Fab")
			(hide yes)
			(effects
				(font
					(size 1.016 1.016)
					(thickness 0.1524)
				)
			)
		)
		(duplicate_pad_numbers_are_jumpers no)
		(fp_line
			(start -0.889 -1.9304)
			(end 0.889 -1.9304)
			(stroke
				(width 0.1524)
				(type default)
			)
			(layer "F.SilkS")
		)
		(fp_line
			(start -0.889 2.159)
			(end -0.889 -1.9304)
			(stroke
				(width 0.1524)
				(type default)
			)
			(layer "F.SilkS")
		)
		(fp_line
			(start 0.762 2.0574)
			(end -0.762 2.0574)
			(stroke
				(width 0.508)
				(type default)
			)
			(layer "F.SilkS")
		)
		(fp_line
			(start 0.889 -1.9304)
			(end 0.889 2.159)
			(stroke
				(width 0.1524)
				(type default)
			)
			(layer "F.SilkS")
		)
		(fp_line
			(start 0.889 2.159)
			(end -0.889 2.159)
			(stroke
				(width 0.1524)
				(type default)
			)
			(layer "F.SilkS")
		)
		(fp_rect
			(start -1.016 2.3114)
			(end 1.016 -2.0066)
			(stroke
				(width 0)
				(type default)
			)
			(fill no)
			(layer "F.CrtYd")
		)
		(fp_poly
			(pts
				(xy -1.016 -2.0066) (xy 1.016 -2.0066) (xy 1.016 2.3114) (xy -1.016 2.3114)
			)
			(stroke
				(width 0)
				(type default)
			)
			(fill no)
			(layer "F.Fab")
		)
		(pad "A" smd rect
			(at 0 -1.143)
			(size 0.5588 1.016)
			(layers "F.Cu" "F.Mask" "F.Paste")
			(net "SW_SSD6_R")
		)
		(pad "K" smd rect
			(at 0 1.143)
			(size 0.5588 1.016)
			(layers "F.Cu" "F.Mask" "F.Paste")
			(net "SW_SSD6_N")
		)
	)
	(footprint ""
		(layer "F.Cu")
		(at 74.041 -454.66)
		(property "Reference" "R345"
			(at 0 0 0)
			(layer "F.SilkS")
			(hide yes)
			(effects
				(font
					(size 1.27 1.27)
				)
			)
		)
		(property "Value" "4K7R2J-2-GP"
			(at 0.064008 -3.993896 0)
			(unlocked yes)
			(layer "F.Fab")
			(hide yes)
			(effects
				(font
					(size 1.016 1.016)
					(thickness 0.1524)
				)
			)
		)
		(property "Device Type" "R402H16"
			(at 0.064008 -5.517896 0)
			(unlocked yes)
			(layer "F.Fab")
			(hide yes)
			(effects
				(font
					(size 1.016 1.016)
					(thickness 0.1524)
				)
			)
		)
		(duplicate_pad_numbers_are_jumpers no)
		(fp_line
			(start -0.508 -0.9398)
			(end -0.508 0.9398)
			(stroke
				(width 0.1524)
				(type default)
			)
			(layer "F.SilkS")
		)
		(fp_line
			(start 0.508 -0.9398)
			(end -0.508 -0.9398)
			(stroke
				(width 0.1524)
				(type default)
			)
			(layer "F.SilkS")
		)
		(fp_rect
			(start -0.508 0.9398)
			(end 0.508 -0.9398)
			(stroke
				(width 0)
				(type default)
			)
			(fill no)
			(layer "F.CrtYd")
		)
		(fp_rect
			(start -0.508 0.9398)
			(end 0.508 -0.9398)
			(stroke
				(width 0)
				(type default)
			)
			(fill no)
			(layer "F.Fab")
		)
		(pad "1" smd custom
			(at 0 -0.4445)
			(size 0.1397 0.1397)
			(layers "F.Cu" "F.Mask" "F.Paste")
			(net "P3V3")
			(options
				(clearance outline)
				(anchor circle)
			)
			(primitives
				(gr_poly
					(pts
						(arc
							(start -0.1778 -0.2794)
							(mid -0.249642 -0.249642)
							(end -0.2794 -0.1778)
						)
						(arc
							(start -0.2794 0.1778)
							(mid -0.249642 0.249642)
							(end -0.1778 0.2794)
						)
						(arc
							(start 0.1778 0.2794)
							(mid 0.249642 0.249642)
							(end 0.2794 0.1778)
						)
						(arc
							(start 0.2794 -0.1778)
							(mid 0.249642 -0.249642)
							(end 0.1778 -0.2794)
						)
					)
					(width 0)
					(fill yes)
				)
			)
		)
		(pad "2" smd custom
			(at 0 0.4445)
			(size 0.1397 0.1397)
			(layers "F.Cu" "F.Mask" "F.Paste")
			(net "EEPROM_A0")
			(options
				(clearance outline)
				(anchor circle)
			)
			(primitives
				(gr_poly
					(pts
						(arc
							(start -0.1778 -0.2794)
							(mid -0.249642 -0.249642)
							(end -0.2794 -0.1778)
						)
						(arc
							(start -0.2794 0.1778)
							(mid -0.249642 0.249642)
							(end -0.1778 0.2794)
						)
						(arc
							(start 0.1778 0.2794)
							(mid 0.249642 0.249642)
							(end 0.2794 0.1778)
						)
						(arc
							(start 0.2794 -0.1778)
							(mid 0.249642 -0.249642)
							(end 0.1778 -0.2794)
						)
					)
					(width 0)
					(fill yes)
				)
			)
		)
	)
)
